# T6G (Grand Teton) — schematic netlist excerpt (pin names and nets, part order shuffled) for the footprints in the layout excerpt that follows; sources: Cadence DE-HDL packaged netlist, KiCad conversion of 04192023_DAF0TMB3IC0_F0TG_MB_C_brd_V02_OCP.brd

R1651  Q_RES  0 5% CHIP  pkg 0402LF  page 174 : A = JTAG_CPU1_R_TDI ; B = JTAG_CPU1_TDI
C902  Q_CAP_DIFFBUS  DIFF BUS_0.22UF 6.3V 20% X6S  pkg C0201  page 63 : \1\ = P5E_CPU0_P0_TX_C_DN<15> ; \2\ = P5E_CPU0_P0_TX_DN<15>
R815  Q_RES  10K 5% EMPTY  pkg 0402LF  page 164 : A = PVDD18_S5_P0 ; B = UART_CPU0_SCM_UART1_TX

(kicad_pcb
	(version 20260206)
	(generator "pcbnew")
	(generator_version "10.0")
	(general
		(thickness 1.6)
		(legacy_teardrops no)
	)
	(paper "A4")
	(title_block
		(title "04192023_DAF0TMB3IC0_F0TG_MB_C_brd_V02_OCP.brd")
		(comment 1 "Grand Teton / footprints 3150-3152 of 8354")
	)
	(layers
		(0 "F.Cu" signal "TOP")
		(4 "In1.Cu" signal "GND")
		(6 "In2.Cu" signal "IN1")
		(8 "In3.Cu" signal "GND1")
		(10 "In4.Cu" signal "IN2")
		(12 "In5.Cu" signal "GND2")
		(14 "In6.Cu" signal "IN3")
		(16 "In7.Cu" signal "GND3")
		(18 "In8.Cu" signal "VCC")
		(20 "In9.Cu" signal "VCC1")
		(22 "In10.Cu" signal "GND4")
		(24 "In11.Cu" signal "IN4")
		(26 "In12.Cu" signal "GND5")
		(28 "In13.Cu" signal "IN5")
		(30 "In14.Cu" signal "GND6")
		(32 "In15.Cu" signal "IN6")
		(34 "In16.Cu" signal "GND7")
		(2 "B.Cu" signal "BOTTOM")
		(9 "F.Adhes" user "F.Adhesive")
		(11 "B.Adhes" user "B.Adhesive")
		(13 "F.Paste" user "Package Geometry/Pastemask Top")
		(15 "B.Paste" user "Package Geometry/Pastemask Bottom")
		(5 "F.SilkS" user "Ref Des/Silkscreen Top")
		(7 "B.SilkS" user "Ref Des/Silkscreen Bottom")
		(1 "F.Mask" user "Board Geometry/Soldermask Top")
		(3 "B.Mask" user "Board Geometry/Soldermask Bottom")
		(17 "Dwgs.User" user "User.Drawings")
		(19 "Cmts.User" user "User.Comments")
		(21 "Eco1.User" user "User.Eco1")
		(23 "Eco2.User" user "User.Eco2")
		(25 "Edge.Cuts" user "Board Geometry/Outline")
		(27 "Margin" user)
		(31 "F.CrtYd" user "Package Geometry/Place Bound Top")
		(29 "B.CrtYd" user "Package Geometry/Place Bound Bottom")
		(35 "F.Fab" user "Ref Des/Assembly Top")
		(33 "B.Fab" user "Ref Des/Assembly Bottom")
	)
	(footprint ""
		(layer "F.Cu")
		(at 369.511326 -43.235118 -90)
		(property "Reference" "R815"
			(at 0 0 270)
			(layer "F.SilkS")
			(hide yes)
			(effects
				(font
					(size 1.27 1.27)
				)
			)
		)
		(property "Value" ""
			(at 0 0 270)
			(layer "F.Fab")
			(effects
				(font
					(size 1.27 1.27)
				)
			)
		)
		(duplicate_pad_numbers_are_jumpers no)
		(fp_line
			(start -0.7874 0.4064)
			(end -0.7874 -0.4064)
			(stroke
				(width 0.1524)
				(type default)
			)
			(layer "F.SilkS")
		)
		(fp_line
			(start 0.7874 0.4064)
			(end -0.7874 0.4064)
			(stroke
				(width 0.1524)
				(type default)
			)
			(layer "F.SilkS")
		)
		(fp_line
			(start -0.7874 -0.4064)
			(end 0.7874 -0.4064)
			(stroke
				(width 0.1524)
				(type default)
			)
			(layer "F.SilkS")
		)
		(fp_line
			(start 0.7874 -0.4064)
			(end 0.7874 0.4064)
			(stroke
				(width 0.1524)
				(type default)
			)
			(layer "F.SilkS")
		)
		(fp_line
			(start -0.67945 0.3048)
			(end -0.67945 -0.305054)
			(stroke
				(width 0.1)
				(type default)
			)
			(layer "F.Fab")
		)
		(fp_line
			(start -0.12065 0.3048)
			(end -0.67945 0.3048)
			(stroke
				(width 0.1)
				(type default)
			)
			(layer "F.Fab")
		)
		(fp_line
			(start 0.120396 0.3048)
			(end 0.120396 0.2794)
			(stroke
				(width 0.1)
				(type default)
			)
			(layer "F.Fab")
		)
		(fp_line
			(start 0.67945 0.3048)
			(end 0.120396 0.3048)
			(stroke
				(width 0.1)
				(type default)
			)
			(layer "F.Fab")
		)
		(fp_line
			(start -0.12065 0.2794)
			(end -0.12065 0.3048)
			(stroke
				(width 0.1)
				(type default)
			)
			(layer "F.Fab")
		)
		(fp_line
			(start 0.120396 0.2794)
			(end -0.12065 0.2794)
			(stroke
				(width 0.1)
				(type default)
			)
			(layer "F.Fab")
		)
		(fp_line
			(start -0.12065 -0.2794)
			(end 0.12065 -0.2794)
			(stroke
				(width 0.1)
				(type default)
			)
			(layer "F.Fab")
		)
		(fp_line
			(start 0.12065 -0.2794)
			(end 0.12065 -0.3048)
			(stroke
				(width 0.1)
				(type default)
			)
			(layer "F.Fab")
		)
		(fp_line
			(start 0.12065 -0.3048)
			(end 0.67945 -0.3048)
			(stroke
				(width 0.1)
				(type default)
			)
			(layer "F.Fab")
		)
		(fp_line
			(start 0.67945 -0.3048)
			(end 0.67945 0.3048)
			(stroke
				(width 0.1)
				(type default)
			)
			(layer "F.Fab")
		)
		(fp_line
			(start -0.67945 -0.305054)
			(end -0.12065 -0.305054)
			(stroke
				(width 0.1)
				(type default)
			)
			(layer "F.Fab")
		)
		(fp_line
			(start -0.12065 -0.305054)
			(end -0.12065 -0.2794)
			(stroke
				(width 0.1)
				(type default)
			)
			(layer "F.Fab")
		)
		(pad "1" smd circle
			(at -0.40005 0 270)
			(size 0 0)
			(layers "F.Cu" "F.Mask" "F.Paste")
			(net "PVDD18_S5_P0")
		)
		(pad "2" smd circle
			(at 0.40005 0 270)
			(size 0 0)
			(layers "F.Cu" "F.Mask" "F.Paste")
			(net "UART_CPU0_SCM_UART1_TX")
		)
	)
	(footprint ""
		(layer "F.Cu")
		(at 325.740776 -388.767828)
		(property "Reference" "C902"
			(at 0 0 0)
			(layer "F.SilkS")
			(hide yes)
			(effects
				(font
					(size 1.27 1.27)
				)
			)
		)
		(property "Value" ""
			(at 0 0 0)
			(layer "F.Fab")
			(effects
				(font
					(size 1.27 1.27)
				)
			)
		)
		(duplicate_pad_numbers_are_jumpers no)
		(fp_line
			(start -0.299974 -0.150114)
			(end 0.299974 -0.150114)
			(stroke
				(width 0.1)
				(type default)
			)
			(layer "F.Fab")
		)
		(fp_line
			(start -0.299974 0.150114)
			(end -0.299974 -0.150114)
			(stroke
				(width 0.1)
				(type default)
			)
			(layer "F.Fab")
		)
		(fp_line
			(start 0.299974 -0.150114)
			(end 0.299974 0.150114)
			(stroke
				(width 0.1)
				(type default)
			)
			(layer "F.Fab")
		)
		(fp_line
			(start 0.299974 0.150114)
			(end -0.299974 0.150114)
			(stroke
				(width 0.1)
				(type default)
			)
			(layer "F.Fab")
		)
		(pad "1" smd rect
			(at -0.2667 0)
			(size 0.3048 0.381)
			(layers "F.Cu" "F.Mask" "F.Paste")
			(net "P5E_CPU0_P0_TX_C_DN<15>")
		)
		(pad "2" smd rect
			(at 0.2667 0)
			(size 0.3048 0.381)
			(layers "F.Cu" "F.Mask" "F.Paste")
			(net "P5E_CPU0_P0_TX_DN<15>")
		)
	)
	(footprint ""
		(layer "F.Cu")
		(at 240.596674 -155.9941)
		(property "Reference" "R1651"
			(at 0 0 0)
			(layer "F.SilkS")
			(hide yes)
			(effects
				(font
					(size 1.27 1.27)
				)
			)
		)
		(property "Value" ""
			(at 0 0 0)
			(layer "F.Fab")
			(effects
				(font
					(size 1.27 1.27)
				)
			)
		)
		(duplicate_pad_numbers_are_jumpers no)
		(fp_line
			(start -0.7874 -0.4064)
			(end 0.7874 -0.4064)
			(stroke
				(width 0.1524)
				(type default)
			)
			(layer "F.SilkS")
		)
		(fp_line
			(start -0.7874 0.4064)
			(end -0.7874 -0.4064)
			(stroke
				(width 0.1524)
				(type default)
			)
			(layer "F.SilkS")
		)
		(fp_line
			(start 0.7874 -0.4064)
			(end 0.7874 0.4064)
			(stroke
				(width 0.1524)
				(type default)
			)
			(layer "F.SilkS")
		)
		(fp_line
			(start 0.7874 0.4064)
			(end -0.7874 0.4064)
			(stroke
				(width 0.1524)
				(type default)
			)
			(layer "F.SilkS")
		)
		(fp_line
			(start -0.67945 -0.305054)
			(end -0.12065 -0.305054)
			(stroke
				(width 0.1)
				(type default)
			)
			(layer "F.Fab")
		)
		(fp_line
			(start -0.67945 0.3048)
			(end -0.67945 -0.305054)
			(stroke
				(width 0.1)
				(type default)
			)
			(layer "F.Fab")
		)
		(fp_line
			(start -0.12065 -0.305054)
			(end -0.12065 -0.2794)
			(stroke
				(width 0.1)
				(type default)
			)
			(layer "F.Fab")
		)
		(fp_line
			(start -0.12065 -0.2794)
			(end 0.12065 -0.2794)
			(stroke
				(width 0.1)
				(type default)
			)
			(layer "F.Fab")
		)
		(fp_line
			(start -0.12065 0.2794)
			(end -0.12065 0.3048)
			(stroke
				(width 0.1)
				(type default)
			)
			(layer "F.Fab")
		)
		(fp_line
			(start -0.12065 0.3048)
			(end -0.67945 0.3048)
			(stroke
				(width 0.1)
				(type default)
			)
			(layer "F.Fab")
		)
		(fp_line
			(start 0.120396 0.2794)
			(end -0.12065 0.2794)
			(stroke
				(width 0.1)
				(type default)
			)
			(layer "F.Fab")
		)
		(fp_line
			(start 0.120396 0.3048)
			(end 0.120396 0.2794)
			(stroke
				(width 0.1)
				(type default)
			)
			(layer "F.Fab")
		)
		(fp_line
			(start 0.12065 -0.3048)
			(end 0.67945 -0.3048)
			(stroke
				(width 0.1)
				(type default)
			)
			(layer "F.Fab")
		)
		(fp_line
			(start 0.12065 -0.2794)
			(end 0.12065 -0.3048)
			(stroke
				(width 0.1)
				(type default)
			)
			(layer "F.Fab")
		)
		(fp_line
			(start 0.67945 -0.3048)
			(end 0.67945 0.3048)
			(stroke
				(width 0.1)
				(type default)
			)
			(layer "F.Fab")
		)
		(fp_line
			(start 0.67945 0.3048)
			(end 0.120396 0.3048)
			(stroke
				(width 0.1)
				(type default)
			)
			(layer "F.Fab")
		)
		(pad "1" smd circle
			(at -0.40005 0)
			(size 0 0)
			(layers "F.Cu" "F.Mask" "F.Paste")
			(net "JTAG_CPU1_R_TDI")
		)
		(pad "2" smd circle
			(at 0.40005 0)
			(size 0 0)
			(layers "F.Cu" "F.Mask" "F.Paste")
			(net "JTAG_CPU1_TDI")
		)
	)
)
